(kicad_pcb
	(version 20260206)
	(generator "pcbnew")
	(generator_version "10.0")
	(general
		(thickness 1.6)
		(legacy_teardrops no)
	)
	(paper "A4")
	(title_block
		(title "pdpb — Lightning_PDPB_BRD.brd")
		(comment 1 "Lightning (Wiwynn / Facebook NVMe JBOF) / footprints 524-530 of 1140")
	)
	(layers
		(0 "F.Cu" signal "TOP")
		(4 "In1.Cu" signal "L2GND")
		(6 "In2.Cu" signal "L3")
		(8 "In3.Cu" signal "L4VCC")
		(10 "In4.Cu" signal "L5VCC")
		(12 "In5.Cu" signal "L6")
		(14 "In6.Cu" signal "L7GND")
		(2 "B.Cu" signal "BOTTOM")
		(9 "F.Adhes" user "F.Adhesive")
		(11 "B.Adhes" user "B.Adhesive")
		(13 "F.Paste" user "Package Geometry/Pastemask Top")
		(15 "B.Paste" user "Package Geometry/Pastemask Bottom")
		(5 "F.SilkS" user "Ref Des/Silkscreen Top")
		(7 "B.SilkS" user "Ref Des/Silkscreen Bottom")
		(1 "F.Mask" user "Board Geometry/Soldermask Top")
		(3 "B.Mask" user "Board Geometry/Soldermask Bottom")
		(17 "Dwgs.User" user "User.Drawings")
		(19 "Cmts.User" user "User.Comments")
		(21 "Eco1.User" user "User.Eco1")
		(23 "Eco2.User" user "User.Eco2")
		(25 "Edge.Cuts" user "Board Geometry/Outline")
		(27 "Margin" user)
		(31 "F.CrtYd" user "Package Geometry/Place Bound Top")
		(29 "B.CrtYd" user "Package Geometry/Place Bound Bottom")
		(35 "F.Fab" user "Ref Des/Assembly Top")
		(33 "B.Fab" user "Ref Des/Assembly Bottom")
	)
	(footprint ""
		(layer "F.Cu")
		(at 81.661 -362.1278 -90)
		(property "Reference" "SR991"
			(at 0 0 270)
			(layer "F.SilkS")
			(hide yes)
			(effects
				(font
					(size 1.27 1.27)
				)
			)
		)
		(property "Value" "2KR2F-3-GP"
			(at 0.064008 -3.993896 270)
			(unlocked yes)
			(layer "F.Fab")
			(hide yes)
			(effects
				(font
					(size 1.016 1.016)
					(thickness 0.1524)
				)
			)
		)
		(property "Device Type" "R402H16"
			(at 0.064008 -5.517896 270)
			(unlocked yes)
			(layer "F.Fab")
			(hide yes)
			(effects
				(font
					(size 1.016 1.016)
					(thickness 0.1524)
				)
			)
		)
		(duplicate_pad_numbers_are_jumpers no)
		(fp_line
			(start -0.508 -0.9398)
			(end -0.508 0.9398)
			(stroke
				(width 0.1524)
				(type default)
			)
			(layer "F.SilkS")
		)
		(fp_line
			(start 0.508 -0.9398)
			(end -0.508 -0.9398)
			(stroke
				(width 0.1524)
				(type default)
			)
			(layer "F.SilkS")
		)
		(fp_rect
			(start -0.508 0.9398)
			(end 0.508 -0.9398)
			(stroke
				(width 0)
				(type default)
			)
			(fill no)
			(layer "F.CrtYd")
		)
		(fp_rect
			(start -0.508 0.9398)
			(end 0.508 -0.9398)
			(stroke
				(width 0)
				(type default)
			)
			(fill no)
			(layer "F.Fab")
		)
		(pad "1" smd custom
			(at 0 -0.4445 270)
			(size 0.1397 0.1397)
			(layers "F.Cu" "F.Mask" "F.Paste")
			(net "P3V3")
			(options
				(clearance outline)
				(anchor circle)
			)
			(primitives
				(gr_poly
					(pts
						(arc
							(start -0.1778 -0.2794)
							(mid -0.249642 -0.249642)
							(end -0.2794 -0.1778)
						)
						(arc
							(start -0.2794 0.1778)
							(mid -0.249642 0.249642)
							(end -0.1778 0.2794)
						)
						(arc
							(start 0.1778 0.2794)
							(mid 0.249642 0.249642)
							(end 0.2794 0.1778)
						)
						(arc
							(start 0.2794 -0.1778)
							(mid 0.249642 -0.249642)
							(end 0.1778 -0.2794)
						)
					)
					(width 0)
					(fill yes)
				)
			)
		)
		(pad "2" smd custom
			(at 0 0.4445 270)
			(size 0.1397 0.1397)
			(layers "F.Cu" "F.Mask" "F.Paste")
			(net "SCL_DR1")
			(options
				(clearance outline)
				(anchor circle)
			)
			(primitives
				(gr_poly
					(pts
						(arc
							(start -0.1778 -0.2794)
							(mid -0.249642 -0.249642)
							(end -0.2794 -0.1778)
						)
						(arc
							(start -0.2794 0.1778)
							(mid -0.249642 0.249642)
							(end -0.1778 0.2794)
						)
						(arc
							(start 0.1778 0.2794)
							(mid 0.249642 0.249642)
							(end 0.2794 0.1778)
						)
						(arc
							(start 0.2794 -0.1778)
							(mid 0.249642 -0.249642)
							(end 0.1778 -0.2794)
						)
					)
					(width 0)
					(fill yes)
				)
			)
		)
	)
	(footprint ""
		(layer "F.Cu")
		(at 46.609 -133.858 -90)
		(property "Reference" "R321"
			(at 0 0 270)
			(layer "F.SilkS")
			(hide yes)
			(effects
				(font
					(size 1.27 1.27)
				)
			)
		)
		(property "Value" "0R2J-2-GP"
			(at 0.064008 -3.993896 270)
			(unlocked yes)
			(layer "F.Fab")
			(hide yes)
			(effects
				(font
					(size 1.016 1.016)
					(thickness 0.1524)
				)
			)
		)
		(property "Device Type" "R402H16"
			(at 0.064008 -5.517896 270)
			(unlocked yes)
			(layer "F.Fab")
			(hide yes)
			(effects
				(font
					(size 1.016 1.016)
					(thickness 0.1524)
				)
			)
		)
		(duplicate_pad_numbers_are_jumpers no)
		(fp_line
			(start -0.508 -0.9398)
			(end -0.508 0.9398)
			(stroke
				(width 0.1524)
				(type default)
			)
			(layer "F.SilkS")
		)
		(fp_line
			(start 0.508 -0.9398)
			(end -0.508 -0.9398)
			(stroke
				(width 0.1524)
				(type default)
			)
			(layer "F.SilkS")
		)
		(fp_rect
			(start -0.508 0.9398)
			(end 0.508 -0.9398)
			(stroke
				(width 0)
				(type default)
			)
			(fill no)
			(layer "F.CrtYd")
		)
		(fp_rect
			(start -0.508 0.9398)
			(end 0.508 -0.9398)
			(stroke
				(width 0)
				(type default)
			)
			(fill no)
			(layer "F.Fab")
		)
		(pad "1" smd custom
			(at 0 -0.4445 270)
			(size 0.1397 0.1397)
			(layers "F.Cu" "F.Mask" "F.Paste")
			(net "I2C_B_SCL")
			(options
				(clearance outline)
				(anchor circle)
			)
			(primitives
				(gr_poly
					(pts
						(arc
							(start -0.1778 -0.2794)
							(mid -0.249642 -0.249642)
							(end -0.2794 -0.1778)
						)
						(arc
							(start -0.2794 0.1778)
							(mid -0.249642 0.249642)
							(end -0.1778 0.2794)
						)
						(arc
							(start 0.1778 0.2794)
							(mid 0.249642 0.249642)
							(end 0.2794 0.1778)
						)
						(arc
							(start 0.2794 -0.1778)
							(mid 0.249642 -0.249642)
							(end 0.1778 -0.2794)
						)
					)
					(width 0)
					(fill yes)
				)
			)
		)
		(pad "2" smd custom
			(at 0 0.4445 270)
			(size 0.1397 0.1397)
			(layers "F.Cu" "F.Mask" "F.Paste")
			(net "TMP1_SCL")
			(options
				(clearance outline)
				(anchor circle)
			)
			(primitives
				(gr_poly
					(pts
						(arc
							(start -0.1778 -0.2794)
							(mid -0.249642 -0.249642)
							(end -0.2794 -0.1778)
						)
						(arc
							(start -0.2794 0.1778)
							(mid -0.249642 0.249642)
							(end -0.1778 0.2794)
						)
						(arc
							(start 0.1778 0.2794)
							(mid 0.249642 0.249642)
							(end 0.2794 0.1778)
						)
						(arc
							(start 0.2794 -0.1778)
							(mid 0.249642 -0.249642)
							(end 0.1778 -0.2794)
						)
					)
					(width 0)
					(fill yes)
				)
			)
		)
	)
	(footprint ""
		(layer "F.Cu")
		(at 96.647 -291.719 180)
		(property "Reference" "R9592"
			(at 0 0 180)
			(layer "F.SilkS")
			(hide yes)
			(effects
				(font
					(size 1.27 1.27)
				)
			)
		)
		(property "Value" "10R2F-L-GP"
			(at 0.064008 -3.993896 180)
			(unlocked yes)
			(layer "F.Fab")
			(hide yes)
			(effects
				(font
					(size 1.016 1.016)
					(thickness 0.1524)
				)
			)
		)
		(property "Device Type" "R402H14"
			(at 0.064008 -5.517896 180)
			(unlocked yes)
			(layer "F.Fab")
			(hide yes)
			(effects
				(font
					(size 1.016 1.016)
					(thickness 0.1524)
				)
			)
		)
		(duplicate_pad_numbers_are_jumpers no)
		(fp_line
			(start 0.508 -0.9398)
			(end -0.508 -0.9398)
			(stroke
				(width 0.1524)
				(type default)
			)
			(layer "F.SilkS")
		)
		(fp_line
			(start -0.508 -0.9398)
			(end -0.508 0.9398)
			(stroke
				(width 0.1524)
				(type default)
			)
			(layer "F.SilkS")
		)
		(fp_rect
			(start -0.508 0.9398)
			(end 0.508 -0.9398)
			(stroke
				(width 0)
				(type default)
			)
			(fill no)
			(layer "F.CrtYd")
		)
		(fp_rect
			(start -0.508 0.9398)
			(end 0.508 -0.9398)
			(stroke
				(width 0)
				(type default)
			)
			(fill no)
			(layer "F.Fab")
		)
		(pad "1" smd custom
			(at 0 -0.4445 180)
			(size 0.1397 0.1397)
			(layers "F.Cu" "F.Mask" "F.Paste")
			(net "SSD_PRSNT_NET2")
			(options
				(clearance outline)
				(anchor circle)
			)
			(primitives
				(gr_poly
					(pts
						(arc
							(start -0.1778 -0.2794)
							(mid -0.249642 -0.249642)
							(end -0.2794 -0.1778)
						)
						(arc
							(start -0.2794 0.1778)
							(mid -0.249642 0.249642)
							(end -0.1778 0.2794)
						)
						(arc
							(start 0.1778 0.2794)
							(mid 0.249642 0.249642)
							(end 0.2794 0.1778)
						)
						(arc
							(start 0.2794 -0.1778)
							(mid 0.249642 -0.249642)
							(end 0.1778 -0.2794)
						)
					)
					(width 0)
					(fill yes)
				)
			)
		)
		(pad "2" smd custom
			(at 0 0.4445 180)
			(size 0.1397 0.1397)
			(layers "F.Cu" "F.Mask" "F.Paste")
			(net "SSD_PRSNT2")
			(options
				(clearance outline)
				(anchor circle)
			)
			(primitives
				(gr_poly
					(pts
						(arc
							(start -0.1778 -0.2794)
							(mid -0.249642 -0.249642)
							(end -0.2794 -0.1778)
						)
						(arc
							(start -0.2794 0.1778)
							(mid -0.249642 0.249642)
							(end -0.1778 0.2794)
						)
						(arc
							(start 0.1778 0.2794)
							(mid 0.249642 0.249642)
							(end 0.2794 0.1778)
						)
						(arc
							(start 0.2794 -0.1778)
							(mid 0.249642 -0.249642)
							(end 0.1778 -0.2794)
						)
					)
					(width 0)
					(fill yes)
				)
			)
		)
	)
	(footprint ""
		(layer "F.Cu")
		(at 228.499924 -144.100042)
		(property "Reference" "LED3"
			(at 0 0 0)
			(layer "F.SilkS")
			(hide yes)
			(effects
				(font
					(size 1.27 1.27)
				)
			)
		)
		(property "Value" "LED-RB-4-GP"
			(at 5.88899 1.80848 0)
			(unlocked yes)
			(layer "F.Fab")
			(hide yes)
			(effects
				(font
					(size 1.016 1.016)
					(thickness 0.1524)
				)
			)
		)
		(property "Device Type" "LED1613-4PH20"
			(at 5.88899 0.28448 0)
			(unlocked yes)
			(layer "F.Fab")
			(hide yes)
			(effects
				(font
					(size 1.016 1.016)
					(thickness 0.1524)
				)
			)
		)
		(duplicate_pad_numbers_are_jumpers no)
		(fp_line
			(start -1.4478 -0.9652)
			(end 1.4478 -0.9652)
			(stroke
				(width 0.1524)
				(type default)
			)
			(layer "F.SilkS")
		)
		(fp_line
			(start -1.4478 0.9652)
			(end -1.4478 -0.9652)
			(stroke
				(width 0.1524)
				(type default)
			)
			(layer "F.SilkS")
		)
		(fp_line
			(start -1.4478 0.9652)
			(end -1.4478 -0.9652)
			(stroke
				(width 0.508)
				(type default)
			)
			(layer "F.SilkS")
		)
		(fp_line
			(start 1.4478 -0.9652)
			(end 1.4478 0.9652)
			(stroke
				(width 0.1524)
				(type default)
			)
			(layer "F.SilkS")
		)
		(fp_line
			(start 1.4478 0.9652)
			(end -1.4478 0.9652)
			(stroke
				(width 0.1524)
				(type default)
			)
			(layer "F.SilkS")
		)
		(fp_rect
			(start -0.8001 0.6477)
			(end 0.8001 -0.6477)
			(stroke
				(width 0)
				(type default)
			)
			(fill no)
			(layer "F.CrtYd")
		)
		(fp_poly
			(pts
				(xy -1.7018 1.2192) (xy -1.7018 -0.06223) (xy -0.8001 -0.06223) (xy -0.8001 0.6477) (xy 0.8001 0.6477)
				(xy 0.8001 -0.6477) (xy -0.8001 -0.6477) (xy -0.8001 -0.0635) (xy -1.7018 -0.0635) (xy -1.7018 -1.2192)
				(xy 1.7018 -1.2192) (xy 1.7018 1.2192)
			)
			(stroke
				(width 0)
				(type default)
			)
			(fill no)
			(layer "F.CrtYd")
		)
		(fp_rect
			(start -1.7018 1.2192)
			(end 1.7018 -1.2192)
			(stroke
				(width 0)
				(type default)
			)
			(fill no)
			(layer "F.Fab")
		)
		(pad "1" smd rect
			(at -0.73025 0.4064)
			(size 0.9144 0.6096)
			(layers "F.Cu" "F.Mask" "F.Paste")
			(net "SSD_ACT_DR3_MOS_N")
		)
		(pad "2" smd rect
			(at -0.73025 -0.4064)
			(size 0.9144 0.6096)
			(layers "F.Cu" "F.Mask" "F.Paste")
			(net "ATTN_LED_DR3_MOS_N")
		)
		(pad "3" smd rect
			(at 0.73025 -0.4064)
			(size 0.9144 0.6096)
			(layers "F.Cu" "F.Mask" "F.Paste")
			(net "DRV_ATTN_3")
		)
		(pad "4" smd rect
			(at 0.73025 0.4064)
			(size 0.9144 0.6096)
			(layers "F.Cu" "F.Mask" "F.Paste")
			(net "DRV_ACT_3")
		)
	)
	(footprint ""
		(layer "F.Cu")
		(at 221.615 -371.348 180)
		(property "Reference" "PC1239"
			(at 0 0 180)
			(layer "F.SilkS")
			(hide yes)
			(effects
				(font
					(size 1.27 1.27)
				)
			)
		)
		(property "Value" "SCD1U25V3KX-GP"
			(at 0 -2.8194 180)
			(unlocked yes)
			(layer "F.Fab")
			(hide yes)
			(effects
				(font
					(size 1.016 1.016)
					(thickness 0.1524)
				)
			)
		)
		(property "Device Type" "C603H36"
			(at 0 -4.3434 180)
			(unlocked yes)
			(layer "F.Fab")
			(hide yes)
			(effects
				(font
					(size 1.016 1.016)
					(thickness 0.1524)
				)
			)
		)
		(duplicate_pad_numbers_are_jumpers no)
		(fp_line
			(start 0.508 0)
			(end -0.508 0)
			(stroke
				(width 0.2032)
				(type default)
			)
			(layer "F.SilkS")
		)
		(fp_rect
			(start -0.5842 1.3335)
			(end 0.5842 -1.3335)
			(stroke
				(width 0)
				(type default)
			)
			(fill no)
			(layer "F.CrtYd")
		)
		(fp_rect
			(start -0.5842 1.3335)
			(end 0.5842 -1.3335)
			(stroke
				(width 0)
				(type default)
			)
			(fill no)
			(layer "F.Fab")
		)
		(pad "1" smd custom
			(at 0 -0.762 180)
			(size 0.2159 0.2159)
			(layers "F.Cu" "F.Mask" "F.Paste")
			(net "P3V3")
			(options
				(clearance outline)
				(anchor circle)
			)
			(primitives
				(gr_poly
					(pts
						(arc
							(start -0.3302 -0.4318)
							(mid -0.402042 -0.402042)
							(end -0.4318 -0.3302)
						)
						(arc
							(start -0.4318 0.3302)
							(mid -0.402042 0.402042)
							(end -0.3302 0.4318)
						)
						(arc
							(start 0.3302 0.4318)
							(mid 0.402042 0.402042)
							(end 0.4318 0.3302)
						)
						(arc
							(start 0.4318 -0.3302)
							(mid 0.402042 -0.402042)
							(end 0.3302 -0.4318)
						)
					)
					(width 0)
					(fill yes)
				)
			)
		)
		(pad "2" smd custom
			(at 0 0.762 180)
			(size 0.2159 0.2159)
			(layers "F.Cu" "F.Mask" "F.Paste")
			(net "GND")
			(options
				(clearance outline)
				(anchor circle)
			)
			(primitives
				(gr_poly
					(pts
						(arc
							(start -0.3302 -0.4318)
							(mid -0.402042 -0.402042)
							(end -0.4318 -0.3302)
						)
						(arc
							(start -0.4318 0.3302)
							(mid -0.402042 0.402042)
							(end -0.3302 0.4318)
						)
						(arc
							(start 0.3302 0.4318)
							(mid 0.402042 0.402042)
							(end 0.4318 0.3302)
						)
						(arc
							(start 0.4318 -0.3302)
							(mid 0.402042 -0.402042)
							(end 0.3302 -0.4318)
						)
					)
					(width 0)
					(fill yes)
				)
			)
		)
	)
	(footprint ""
		(layer "F.Cu")
		(at 70.231 -440.182)
		(property "Reference" "R352"
			(at 0 0 0)
			(layer "F.SilkS")
			(hide yes)
			(effects
				(font
					(size 1.27 1.27)
				)
			)
		)
		(property "Value" "0R2J-2-GP"
			(at 0.064008 -3.993896 0)
			(unlocked yes)
			(layer "F.Fab")
			(hide yes)
			(effects
				(font
					(size 1.016 1.016)
					(thickness 0.1524)
				)
			)
		)
		(property "Device Type" "R402H16"
			(at 0.064008 -5.517896 0)
			(unlocked yes)
			(layer "F.Fab")
			(hide yes)
			(effects
				(font
					(size 1.016 1.016)
					(thickness 0.1524)
				)
			)
		)
		(duplicate_pad_numbers_are_jumpers no)
		(fp_line
			(start -0.508 -0.9398)
			(end -0.508 0.9398)
			(stroke
				(width 0.1524)
				(type default)
			)
			(layer "F.SilkS")
		)
		(fp_line
			(start 0.508 -0.9398)
			(end -0.508 -0.9398)
			(stroke
				(width 0.1524)
				(type default)
			)
			(layer "F.SilkS")
		)
		(fp_rect
			(start -0.508 0.9398)
			(end 0.508 -0.9398)
			(stroke
				(width 0)
				(type default)
			)
			(fill no)
			(layer "F.CrtYd")
		)
		(fp_rect
			(start -0.508 0.9398)
			(end 0.508 -0.9398)
			(stroke
				(width 0)
				(type default)
			)
			(fill no)
			(layer "F.Fab")
		)
		(pad "1" smd custom
			(at 0 -0.4445)
			(size 0.1397 0.1397)
			(layers "F.Cu" "F.Mask" "F.Paste")
			(net "EEPROM_SCL")
			(options
				(clearance outline)
				(anchor circle)
			)
			(primitives
				(gr_poly
					(pts
						(arc
							(start -0.1778 -0.2794)
							(mid -0.249642 -0.249642)
							(end -0.2794 -0.1778)
						)
						(arc
							(start -0.2794 0.1778)
							(mid -0.249642 0.249642)
							(end -0.1778 0.2794)
						)
						(arc
							(start 0.1778 0.2794)
							(mid 0.249642 0.249642)
							(end 0.2794 0.1778)
						)
						(arc
							(start 0.2794 -0.1778)
							(mid 0.249642 -0.249642)
							(end 0.1778 -0.2794)
						)
					)
					(width 0)
					(fill yes)
				)
			)
		)
		(pad "2" smd custom
			(at 0 0.4445)
			(size 0.1397 0.1397)
			(layers "F.Cu" "F.Mask" "F.Paste")
			(net "I2C_B_SCL")
			(options
				(clearance outline)
				(anchor circle)
			)
			(primitives
				(gr_poly
					(pts
						(arc
							(start -0.1778 -0.2794)
							(mid -0.249642 -0.249642)
							(end -0.2794 -0.1778)
						)
						(arc
							(start -0.2794 0.1778)
							(mid -0.249642 0.249642)
							(end -0.1778 0.2794)
						)
						(arc
							(start 0.1778 0.2794)
							(mid 0.249642 0.249642)
							(end 0.2794 0.1778)
						)
						(arc
							(start 0.2794 -0.1778)
							(mid 0.249642 -0.249642)
							(end 0.1778 -0.2794)
						)
					)
					(width 0)
					(fill yes)
				)
			)
		)
	)
	(footprint ""
		(layer "F.Cu")
		(at 16.72336 -360.14914 90)
		(property "Reference" "R9950"
			(at 0 0 90)
			(layer "F.SilkS")
			(hide yes)
			(effects
				(font
					(size 1.27 1.27)
				)
			)
		)
		(property "Value" "4K7R2J-2-GP"
			(at 0.064008 -3.993896 90)
			(unlocked yes)
			(layer "F.Fab")
			(hide yes)
			(effects
				(font
					(size 1.016 1.016)
					(thickness 0.1524)
				)
			)
		)
		(property "Device Type" "R402H16"
			(at 0.064008 -5.517896 90)
			(unlocked yes)
			(layer "F.Fab")
			(hide yes)
			(effects
				(font
					(size 1.016 1.016)
					(thickness 0.1524)
				)
			)
		)
		(duplicate_pad_numbers_are_jumpers no)
		(fp_line
			(start 0.508 -0.9398)
			(end -0.508 -0.9398)
			(stroke
				(width 0.1524)
				(type default)
			)
			(layer "F.SilkS")
		)
		(fp_line
			(start -0.508 -0.9398)
			(end -0.508 0.9398)
			(stroke
				(width 0.1524)
				(type default)
			)
			(layer "F.SilkS")
		)
		(fp_rect
			(start -0.508 0.9398)
			(end 0.508 -0.9398)
			(stroke
				(width 0)
				(type default)
			)
			(fill no)
			(layer "F.CrtYd")
		)
		(fp_rect
			(start -0.508 0.9398)
			(end 0.508 -0.9398)
			(stroke
				(width 0)
				(type default)
			)
			(fill no)
			(layer "F.Fab")
		)
		(pad "1" smd custom
			(at 0 -0.4445 90)
			(size 0.1397 0.1397)
			(layers "F.Cu" "F.Mask" "F.Paste")
			(net "P3V3")
			(options
				(clearance outline)
				(anchor circle)
			)
			(primitives
				(gr_poly
					(pts
						(arc
							(start -0.1778 -0.2794)
							(mid -0.249642 -0.249642)
							(end -0.2794 -0.1778)
						)
						(arc
							(start -0.2794 0.1778)
							(mid -0.249642 0.249642)
							(end -0.1778 0.2794)
						)
						(arc
							(start 0.1778 0.2794)
							(mid 0.249642 0.249642)
							(end 0.2794 0.1778)
						)
						(arc
							(start 0.2794 -0.1778)
							(mid 0.249642 -0.249642)
							(end 0.1778 -0.2794)
						)
					)
					(width 0)
					(fill yes)
				)
			)
		)
		(pad "2" smd custom
			(at 0 0.4445 90)
			(size 0.1397 0.1397)
			(layers "F.Cu" "F.Mask" "F.Paste")
			(net "SSD_ACT_DR11_MOS_N")
			(options
				(clearance outline)
				(anchor circle)
			)
			(primitives
				(gr_poly
					(pts
						(arc
							(start -0.1778 -0.2794)
							(mid -0.249642 -0.249642)
							(end -0.2794 -0.1778)
						)
						(arc
							(start -0.2794 0.1778)
							(mid -0.249642 0.249642)
							(end -0.1778 0.2794)
						)
						(arc
							(start 0.1778 0.2794)
							(mid 0.249642 0.249642)
							(end 0.2794 0.1778)
						)
						(arc
							(start 0.2794 -0.1778)
							(mid 0.249642 -0.249642)
							(end 0.1778 -0.2794)
						)
					)
					(width 0)
					(fill yes)
				)
			)
		)
	)
)
